(kicad_pcb
	(version 20260206)
	(generator "pcbnew")
	(generator_version "10.0")
	(general
		(thickness 1.6)
		(legacy_teardrops no)
	)
	(paper "A4")
	(title_block
		(title "03242023_DA0F0TMBIJ0_F0T_Motherboard_J_brd_V01_OCP.brd")
		(comment 1 "Grand Teton / footprints 1701-1706 of 6105")
	)
	(layers
		(0 "F.Cu" signal "TOP")
		(4 "In1.Cu" signal "GND")
		(6 "In2.Cu" signal "IN1")
		(8 "In3.Cu" signal "GND1")
		(10 "In4.Cu" signal "IN2")
		(12 "In5.Cu" signal "GND2")
		(14 "In6.Cu" signal "IN3")
		(16 "In7.Cu" signal "GND3")
		(18 "In8.Cu" signal "VCC")
		(20 "In9.Cu" signal "VCC1")
		(22 "In10.Cu" signal "GND4")
		(24 "In11.Cu" signal "IN4")
		(26 "In12.Cu" signal "GND5")
		(28 "In13.Cu" signal "IN5")
		(30 "In14.Cu" signal "GND6")
		(32 "In15.Cu" signal "IN6")
		(34 "In16.Cu" signal "GND7")
		(2 "B.Cu" signal "BOTTOM")
		(9 "F.Adhes" user "F.Adhesive")
		(11 "B.Adhes" user "B.Adhesive")
		(13 "F.Paste" user "Package Geometry/Pastemask Top")
		(15 "B.Paste" user "Package Geometry/Pastemask Bottom")
		(5 "F.SilkS" user "Ref Des/Silkscreen Top")
		(7 "B.SilkS" user "Ref Des/Silkscreen Bottom")
		(1 "F.Mask" user "Board Geometry/Soldermask Top")
		(3 "B.Mask" user "Board Geometry/Soldermask Bottom")
		(17 "Dwgs.User" user "User.Drawings")
		(19 "Cmts.User" user "User.Comments")
		(21 "Eco1.User" user "User.Eco1")
		(23 "Eco2.User" user "User.Eco2")
		(25 "Edge.Cuts" user "Board Geometry/Outline")
		(27 "Margin" user)
		(31 "F.CrtYd" user "Package Geometry/Place Bound Top")
		(29 "B.CrtYd" user "Package Geometry/Place Bound Bottom")
		(35 "F.Fab" user "Ref Des/Assembly Top")
		(33 "B.Fab" user "Ref Des/Assembly Bottom")
	)
	(footprint ""
		(layer "F.Cu")
		(at 432.41468 -176.61382)
		(property "Reference" "PR50"
			(at 0 0 0)
			(layer "F.SilkS")
			(hide yes)
			(effects
				(font
					(size 1.27 1.27)
				)
			)
		)
		(property "Value" ""
			(at 0 0 0)
			(layer "F.Fab")
			(effects
				(font
					(size 1.27 1.27)
				)
			)
		)
		(duplicate_pad_numbers_are_jumpers no)
		(fp_line
			(start -0.7874 -0.4064)
			(end 0.7874 -0.4064)
			(stroke
				(width 0.1524)
				(type default)
			)
			(layer "F.SilkS")
		)
		(fp_line
			(start -0.7874 0.4064)
			(end -0.7874 -0.4064)
			(stroke
				(width 0.1524)
				(type default)
			)
			(layer "F.SilkS")
		)
		(fp_line
			(start 0.7874 -0.4064)
			(end 0.7874 0.4064)
			(stroke
				(width 0.1524)
				(type default)
			)
			(layer "F.SilkS")
		)
		(fp_line
			(start 0.7874 0.4064)
			(end -0.7874 0.4064)
			(stroke
				(width 0.1524)
				(type default)
			)
			(layer "F.SilkS")
		)
		(fp_line
			(start -0.67945 -0.305054)
			(end -0.12065 -0.305054)
			(stroke
				(width 0.1)
				(type default)
			)
			(layer "F.Fab")
		)
		(fp_line
			(start -0.67945 0.3048)
			(end -0.67945 -0.305054)
			(stroke
				(width 0.1)
				(type default)
			)
			(layer "F.Fab")
		)
		(fp_line
			(start -0.12065 -0.305054)
			(end -0.12065 -0.2794)
			(stroke
				(width 0.1)
				(type default)
			)
			(layer "F.Fab")
		)
		(fp_line
			(start -0.12065 -0.2794)
			(end 0.12065 -0.2794)
			(stroke
				(width 0.1)
				(type default)
			)
			(layer "F.Fab")
		)
		(fp_line
			(start -0.12065 0.2794)
			(end -0.12065 0.3048)
			(stroke
				(width 0.1)
				(type default)
			)
			(layer "F.Fab")
		)
		(fp_line
			(start -0.12065 0.3048)
			(end -0.67945 0.3048)
			(stroke
				(width 0.1)
				(type default)
			)
			(layer "F.Fab")
		)
		(fp_line
			(start 0.120396 0.2794)
			(end -0.12065 0.2794)
			(stroke
				(width 0.1)
				(type default)
			)
			(layer "F.Fab")
		)
		(fp_line
			(start 0.120396 0.3048)
			(end 0.120396 0.2794)
			(stroke
				(width 0.1)
				(type default)
			)
			(layer "F.Fab")
		)
		(fp_line
			(start 0.12065 -0.3048)
			(end 0.67945 -0.3048)
			(stroke
				(width 0.1)
				(type default)
			)
			(layer "F.Fab")
		)
		(fp_line
			(start 0.12065 -0.2794)
			(end 0.12065 -0.3048)
			(stroke
				(width 0.1)
				(type default)
			)
			(layer "F.Fab")
		)
		(fp_line
			(start 0.67945 -0.3048)
			(end 0.67945 0.3048)
			(stroke
				(width 0.1)
				(type default)
			)
			(layer "F.Fab")
		)
		(fp_line
			(start 0.67945 0.3048)
			(end 0.120396 0.3048)
			(stroke
				(width 0.1)
				(type default)
			)
			(layer "F.Fab")
		)
		(pad "1" smd circle
			(at -0.40005 0)
			(size 0 0)
			(layers "F.Cu" "F.Mask" "F.Paste")
			(net "PVNN_MAIN_CPU0_FB")
		)
		(pad "2" smd circle
			(at 0.40005 0)
			(size 0 0)
			(layers "F.Cu" "F.Mask" "F.Paste")
			(net "GND")
		)
	)
	(footprint ""
		(layer "F.Cu")
		(at 102.355142 -338.290662 -90)
		(property "Reference" "PC1338"
			(at 0 0 270)
			(layer "F.SilkS")
			(hide yes)
			(effects
				(font
					(size 1.27 1.27)
				)
			)
		)
		(property "Value" ""
			(at 0 0 270)
			(layer "F.Fab")
			(effects
				(font
					(size 1.27 1.27)
				)
			)
		)
		(duplicate_pad_numbers_are_jumpers no)
		(fp_line
			(start -0.7874 0.4064)
			(end -0.7874 -0.4064)
			(stroke
				(width 0.1524)
				(type default)
			)
			(layer "F.SilkS")
		)
		(fp_line
			(start 0.7874 0.4064)
			(end -0.7874 0.4064)
			(stroke
				(width 0.1524)
				(type default)
			)
			(layer "F.SilkS")
		)
		(fp_line
			(start -0.7874 -0.4064)
			(end 0.7874 -0.4064)
			(stroke
				(width 0.1524)
				(type default)
			)
			(layer "F.SilkS")
		)
		(fp_line
			(start 0.7874 -0.4064)
			(end 0.7874 0.4064)
			(stroke
				(width 0.1524)
				(type default)
			)
			(layer "F.SilkS")
		)
		(fp_line
			(start -0.67945 0.3048)
			(end -0.67945 -0.305054)
			(stroke
				(width 0.1)
				(type default)
			)
			(layer "F.Fab")
		)
		(fp_line
			(start -0.12065 0.3048)
			(end -0.67945 0.3048)
			(stroke
				(width 0.1)
				(type default)
			)
			(layer "F.Fab")
		)
		(fp_line
			(start 0.120396 0.3048)
			(end 0.120396 0.2794)
			(stroke
				(width 0.1)
				(type default)
			)
			(layer "F.Fab")
		)
		(fp_line
			(start 0.67945 0.3048)
			(end 0.120396 0.3048)
			(stroke
				(width 0.1)
				(type default)
			)
			(layer "F.Fab")
		)
		(fp_line
			(start -0.12065 0.2794)
			(end -0.12065 0.3048)
			(stroke
				(width 0.1)
				(type default)
			)
			(layer "F.Fab")
		)
		(fp_line
			(start 0.120396 0.2794)
			(end -0.12065 0.2794)
			(stroke
				(width 0.1)
				(type default)
			)
			(layer "F.Fab")
		)
		(fp_line
			(start -0.12065 -0.2794)
			(end 0.12065 -0.2794)
			(stroke
				(width 0.1)
				(type default)
			)
			(layer "F.Fab")
		)
		(fp_line
			(start 0.12065 -0.2794)
			(end 0.12065 -0.3048)
			(stroke
				(width 0.1)
				(type default)
			)
			(layer "F.Fab")
		)
		(fp_line
			(start 0.12065 -0.3048)
			(end 0.67945 -0.3048)
			(stroke
				(width 0.1)
				(type default)
			)
			(layer "F.Fab")
		)
		(fp_line
			(start 0.67945 -0.3048)
			(end 0.67945 0.3048)
			(stroke
				(width 0.1)
				(type default)
			)
			(layer "F.Fab")
		)
		(fp_line
			(start -0.67945 -0.305054)
			(end -0.12065 -0.305054)
			(stroke
				(width 0.1)
				(type default)
			)
			(layer "F.Fab")
		)
		(fp_line
			(start -0.12065 -0.305054)
			(end -0.12065 -0.2794)
			(stroke
				(width 0.1)
				(type default)
			)
			(layer "F.Fab")
		)
		(pad "1" smd circle
			(at -0.40005 0 270)
			(size 0 0)
			(layers "F.Cu" "F.Mask" "F.Paste")
			(net "GND")
		)
		(pad "2" smd circle
			(at 0.40005 0 270)
			(size 0 0)
			(layers "F.Cu" "F.Mask" "F.Paste")
			(net "PVCCIN_CPU1_VREF")
		)
	)
	(footprint ""
		(layer "F.Cu")
		(at 119.508016 -240.277142 90)
		(property "Reference" "C424"
			(at 0 0 90)
			(layer "F.SilkS")
			(hide yes)
			(effects
				(font
					(size 1.27 1.27)
				)
			)
		)
		(property "Value" ""
			(at 0 0 90)
			(layer "F.Fab")
			(effects
				(font
					(size 1.27 1.27)
				)
			)
		)
		(duplicate_pad_numbers_are_jumpers no)
		(fp_line
			(start 0.7874 -0.4064)
			(end 0.7874 0.4064)
			(stroke
				(width 0.1524)
				(type default)
			)
			(layer "F.SilkS")
		)
		(fp_line
			(start -0.7874 -0.4064)
			(end 0.7874 -0.4064)
			(stroke
				(width 0.1524)
				(type default)
			)
			(layer "F.SilkS")
		)
		(fp_line
			(start 0.7874 0.4064)
			(end -0.7874 0.4064)
			(stroke
				(width 0.1524)
				(type default)
			)
			(layer "F.SilkS")
		)
		(fp_line
			(start -0.7874 0.4064)
			(end -0.7874 -0.4064)
			(stroke
				(width 0.1524)
				(type default)
			)
			(layer "F.SilkS")
		)
		(fp_line
			(start -0.12065 -0.305054)
			(end -0.12065 -0.2794)
			(stroke
				(width 0.1)
				(type default)
			)
			(layer "F.Fab")
		)
		(fp_line
			(start -0.67945 -0.305054)
			(end -0.12065 -0.305054)
			(stroke
				(width 0.1)
				(type default)
			)
			(layer "F.Fab")
		)
		(fp_line
			(start 0.67945 -0.3048)
			(end 0.67945 0.3048)
			(stroke
				(width 0.1)
				(type default)
			)
			(layer "F.Fab")
		)
		(fp_line
			(start 0.12065 -0.3048)
			(end 0.67945 -0.3048)
			(stroke
				(width 0.1)
				(type default)
			)
			(layer "F.Fab")
		)
		(fp_line
			(start 0.12065 -0.2794)
			(end 0.12065 -0.3048)
			(stroke
				(width 0.1)
				(type default)
			)
			(layer "F.Fab")
		)
		(fp_line
			(start -0.12065 -0.2794)
			(end 0.12065 -0.2794)
			(stroke
				(width 0.1)
				(type default)
			)
			(layer "F.Fab")
		)
		(fp_line
			(start 0.120396 0.2794)
			(end -0.12065 0.2794)
			(stroke
				(width 0.1)
				(type default)
			)
			(layer "F.Fab")
		)
		(fp_line
			(start -0.12065 0.2794)
			(end -0.12065 0.3048)
			(stroke
				(width 0.1)
				(type default)
			)
			(layer "F.Fab")
		)
		(fp_line
			(start 0.67945 0.3048)
			(end 0.120396 0.3048)
			(stroke
				(width 0.1)
				(type default)
			)
			(layer "F.Fab")
		)
		(fp_line
			(start 0.120396 0.3048)
			(end 0.120396 0.2794)
			(stroke
				(width 0.1)
				(type default)
			)
			(layer "F.Fab")
		)
		(fp_line
			(start -0.12065 0.3048)
			(end -0.67945 0.3048)
			(stroke
				(width 0.1)
				(type default)
			)
			(layer "F.Fab")
		)
		(fp_line
			(start -0.67945 0.3048)
			(end -0.67945 -0.305054)
			(stroke
				(width 0.1)
				(type default)
			)
			(layer "F.Fab")
		)
		(pad "1" smd circle
			(at -0.40005 0 90)
			(size 0 0)
			(layers "F.Cu" "F.Mask" "F.Paste")
			(net "PVCCFA_EHV_FIVRA_CPU1")
		)
		(pad "2" smd circle
			(at 0.40005 0 90)
			(size 0 0)
			(layers "F.Cu" "F.Mask" "F.Paste")
			(net "GND")
		)
	)
	(footprint ""
		(layer "F.Cu")
		(at 111.74222 -296.05478 180)
		(property "Reference" "C225"
			(at 0 0 180)
			(layer "F.SilkS")
			(hide yes)
			(effects
				(font
					(size 1.27 1.27)
				)
			)
		)
		(property "Value" ""
			(at 0 0 180)
			(layer "F.Fab")
			(effects
				(font
					(size 1.27 1.27)
				)
			)
		)
		(duplicate_pad_numbers_are_jumpers no)
		(fp_line
			(start 1.524 0.762)
			(end -1.524 0.762)
			(stroke
				(width 0.1524)
				(type default)
			)
			(layer "F.SilkS")
		)
		(fp_line
			(start 1.524 -0.762)
			(end 1.524 0.762)
			(stroke
				(width 0.1524)
				(type default)
			)
			(layer "F.SilkS")
		)
		(fp_line
			(start -1.524 0.762)
			(end -1.524 -0.762)
			(stroke
				(width 0.1524)
				(type default)
			)
			(layer "F.SilkS")
		)
		(fp_line
			(start -1.524 -0.762)
			(end 1.524 -0.762)
			(stroke
				(width 0.1524)
				(type default)
			)
			(layer "F.SilkS")
		)
		(fp_line
			(start 1.1049 0.724916)
			(end 1.1049 -0.724916)
			(stroke
				(width 0.1)
				(type default)
			)
			(layer "F.Fab")
		)
		(fp_line
			(start 1.1049 -0.724916)
			(end -1.1049 -0.724916)
			(stroke
				(width 0.1)
				(type default)
			)
			(layer "F.Fab")
		)
		(fp_line
			(start -1.1049 0.724916)
			(end 1.1049 0.724916)
			(stroke
				(width 0.1)
				(type default)
			)
			(layer "F.Fab")
		)
		(fp_line
			(start -1.1049 -0.724916)
			(end -1.1049 0.724916)
			(stroke
				(width 0.1)
				(type default)
			)
			(layer "F.Fab")
		)
		(pad "1" smd rect
			(at -0.889 0)
			(size 1.016 1.27)
			(layers "F.Cu" "F.Mask" "F.Paste")
			(net "PVCCIN_CPU1")
		)
		(pad "2" smd rect
			(at 0.889 0)
			(size 1.016 1.27)
			(layers "F.Cu" "F.Mask" "F.Paste")
			(net "GND")
		)
	)
	(footprint ""
		(layer "F.Cu")
		(at 336.406998 -65.015364)
		(property "Reference" "R1316"
			(at 0 0 0)
			(layer "F.SilkS")
			(hide yes)
			(effects
				(font
					(size 1.27 1.27)
				)
			)
		)
		(property "Value" ""
			(at 0 0 0)
			(layer "F.Fab")
			(effects
				(font
					(size 1.27 1.27)
				)
			)
		)
		(duplicate_pad_numbers_are_jumpers no)
		(fp_line
			(start -1.2954 -0.5842)
			(end 1.2954 -0.5842)
			(stroke
				(width 0.1524)
				(type default)
			)
			(layer "F.SilkS")
		)
		(fp_line
			(start -1.2954 0.5842)
			(end -1.2954 -0.5842)
			(stroke
				(width 0.1524)
				(type default)
			)
			(layer "F.SilkS")
		)
		(fp_line
			(start 1.2954 -0.5842)
			(end 1.2954 0.5842)
			(stroke
				(width 0.1524)
				(type default)
			)
			(layer "F.SilkS")
		)
		(fp_line
			(start 1.2954 0.5842)
			(end -1.2954 0.5842)
			(stroke
				(width 0.1524)
				(type default)
			)
			(layer "F.SilkS")
		)
		(fp_line
			(start -1.1938 -0.406654)
			(end -0.8636 -0.406654)
			(stroke
				(width 0.1)
				(type default)
			)
			(layer "F.Fab")
		)
		(fp_line
			(start -1.1938 0.4064)
			(end -1.1938 -0.406654)
			(stroke
				(width 0.1)
				(type default)
			)
			(layer "F.Fab")
		)
		(fp_line
			(start -0.8636 -0.4572)
			(end 0.8636 -0.4572)
			(stroke
				(width 0.1)
				(type default)
			)
			(layer "F.Fab")
		)
		(fp_line
			(start -0.8636 -0.406654)
			(end -0.8636 -0.4572)
			(stroke
				(width 0.1)
				(type default)
			)
			(layer "F.Fab")
		)
		(fp_line
			(start -0.8636 0.4064)
			(end -1.1938 0.4064)
			(stroke
				(width 0.1)
				(type default)
			)
			(layer "F.Fab")
		)
		(fp_line
			(start -0.8636 0.4318)
			(end -0.8636 0.4064)
			(stroke
				(width 0.1)
				(type default)
			)
			(layer "F.Fab")
		)
		(fp_line
			(start -0.8636 0.4572)
			(end -0.8636 0.4318)
			(stroke
				(width 0.1)
				(type default)
			)
			(layer "F.Fab")
		)
		(fp_line
			(start 0.8636 -0.4572)
			(end 0.8636 -0.406654)
			(stroke
				(width 0.1)
				(type default)
			)
			(layer "F.Fab")
		)
		(fp_line
			(start 0.8636 -0.406654)
			(end 1.1938 -0.406654)
			(stroke
				(width 0.1)
				(type default)
			)
			(layer "F.Fab")
		)
		(fp_line
			(start 0.8636 0.4064)
			(end 0.8636 0.4572)
			(stroke
				(width 0.1)
				(type default)
			)
			(layer "F.Fab")
		)
		(fp_line
			(start 0.8636 0.4572)
			(end -0.8636 0.4572)
			(stroke
				(width 0.1)
				(type default)
			)
			(layer "F.Fab")
		)
		(fp_line
			(start 1.1938 -0.406654)
			(end 1.1938 0.4064)
			(stroke
				(width 0.1)
				(type default)
			)
			(layer "F.Fab")
		)
		(fp_line
			(start 1.1938 0.4064)
			(end 0.8636 0.4064)
			(stroke
				(width 0.1)
				(type default)
			)
			(layer "F.Fab")
		)
		(pad "1" smd rect
			(at -0.7366 0 270)
			(size 0.7112 0.8128)
			(layers "F.Cu" "F.Mask" "F.Paste")
			(net "XTAL_PCH_25M_IN_R")
		)
		(pad "2" smd rect
			(at 0.7366 0 270)
			(size 0.7112 0.8128)
			(layers "F.Cu" "F.Mask" "F.Paste")
			(net "XTAL_PCH_25M_OUT")
		)
	)
	(footprint ""
		(layer "F.Cu")
		(at 191.988186 -429.41113 -90)
		(property "Reference" "R2948"
			(at 0 0 270)
			(layer "F.SilkS")
			(hide yes)
			(effects
				(font
					(size 1.27 1.27)
				)
			)
		)
		(property "Value" ""
			(at 0 0 270)
			(layer "F.Fab")
			(effects
				(font
					(size 1.27 1.27)
				)
			)
		)
		(duplicate_pad_numbers_are_jumpers no)
		(fp_line
			(start -0.7874 0.4064)
			(end -0.7874 -0.4064)
			(stroke
				(width 0.1524)
				(type default)
			)
			(layer "F.SilkS")
		)
		(fp_line
			(start 0.7874 0.4064)
			(end -0.7874 0.4064)
			(stroke
				(width 0.1524)
				(type default)
			)
			(layer "F.SilkS")
		)
		(fp_line
			(start -0.7874 -0.4064)
			(end 0.7874 -0.4064)
			(stroke
				(width 0.1524)
				(type default)
			)
			(layer "F.SilkS")
		)
		(fp_line
			(start 0.7874 -0.4064)
			(end 0.7874 0.4064)
			(stroke
				(width 0.1524)
				(type default)
			)
			(layer "F.SilkS")
		)
		(fp_line
			(start -0.67945 0.3048)
			(end -0.67945 -0.305054)
			(stroke
				(width 0.1)
				(type default)
			)
			(layer "F.Fab")
		)
		(fp_line
			(start -0.12065 0.3048)
			(end -0.67945 0.3048)
			(stroke
				(width 0.1)
				(type default)
			)
			(layer "F.Fab")
		)
		(fp_line
			(start 0.120396 0.3048)
			(end 0.120396 0.2794)
			(stroke
				(width 0.1)
				(type default)
			)
			(layer "F.Fab")
		)
		(fp_line
			(start 0.67945 0.3048)
			(end 0.120396 0.3048)
			(stroke
				(width 0.1)
				(type default)
			)
			(layer "F.Fab")
		)
		(fp_line
			(start -0.12065 0.2794)
			(end -0.12065 0.3048)
			(stroke
				(width 0.1)
				(type default)
			)
			(layer "F.Fab")
		)
		(fp_line
			(start 0.120396 0.2794)
			(end -0.12065 0.2794)
			(stroke
				(width 0.1)
				(type default)
			)
			(layer "F.Fab")
		)
		(fp_line
			(start -0.12065 -0.2794)
			(end 0.12065 -0.2794)
			(stroke
				(width 0.1)
				(type default)
			)
			(layer "F.Fab")
		)
		(fp_line
			(start 0.12065 -0.2794)
			(end 0.12065 -0.3048)
			(stroke
				(width 0.1)
				(type default)
			)
			(layer "F.Fab")
		)
		(fp_line
			(start 0.12065 -0.3048)
			(end 0.67945 -0.3048)
			(stroke
				(width 0.1)
				(type default)
			)
			(layer "F.Fab")
		)
		(fp_line
			(start 0.67945 -0.3048)
			(end 0.67945 0.3048)
			(stroke
				(width 0.1)
				(type default)
			)
			(layer "F.Fab")
		)
		(fp_line
			(start -0.67945 -0.305054)
			(end -0.12065 -0.305054)
			(stroke
				(width 0.1)
				(type default)
			)
			(layer "F.Fab")
		)
		(fp_line
			(start -0.12065 -0.305054)
			(end -0.12065 -0.2794)
			(stroke
				(width 0.1)
				(type default)
			)
			(layer "F.Fab")
		)
		(pad "1" smd circle
			(at -0.40005 0 270)
			(size 0 0)
			(layers "F.Cu" "F.Mask" "F.Paste")
			(net "FM_GPU_HSC_EN_BUF_R")
		)
		(pad "2" smd circle
			(at 0.40005 0 270)
			(size 0 0)
			(layers "F.Cu" "F.Mask" "F.Paste")
			(net "GND")
		)
	)
)
